(kicad_pcb
	(version 20241229)
	(generator "pcbnew")
	(generator_version "9.0")
	(general
		(thickness 1.61)
		(legacy_teardrops no)
	)
	(paper "A3")
	(title_block
		(title "RDIMM DDR5 Tester")
		(date "2026-05-21")
		(rev "2.2.0")
		(company "Antmicro")
		(comment 9 "footprints 313-317 of 796")
	)
	(layers
		(0 "F.Cu" signal)
		(4 "In1.Cu" power)
		(6 "In2.Cu" mixed)
		(8 "In3.Cu" power)
		(10 "In4.Cu" mixed)
		(12 "In5.Cu" power)
		(14 "In6.Cu" mixed)
		(16 "In7.Cu" power)
		(18 "In8.Cu" power)
		(20 "In9.Cu" mixed)
		(22 "In10.Cu" power)
		(2 "B.Cu" signal)
		(9 "F.Adhes" user "F.Adhesive")
		(11 "B.Adhes" user "B.Adhesive")
		(13 "F.Paste" user)
		(15 "B.Paste" user)
		(5 "F.SilkS" user "F.Silkscreen")
		(7 "B.SilkS" user "B.Silkscreen")
		(1 "F.Mask" user)
		(3 "B.Mask" user)
		(17 "Dwgs.User" user "User.Drawings")
		(19 "Cmts.User" user "User.Comments")
		(21 "Eco1.User" user "User.Eco1")
		(23 "Eco2.User" user "User.Eco2")
		(25 "Edge.Cuts" user)
		(27 "Margin" user)
		(31 "F.CrtYd" user "F.Courtyard")
		(29 "B.CrtYd" user "B.Courtyard")
		(35 "F.Fab" user)
		(33 "B.Fab" user)
	)
	(footprint "antmicro-footprints:C_0805_2012Metric"
		(layer "F.Cu")
		(at 261.02 172.9095 90)
		(descr "Capacitor SMD 0805")
		(tags "capacitor SMD 0805")
		(property "Reference" "C171"
			(at 1.8595 1.43 90)
			(layer "F.SilkS")
			(effects
				(font
					(size 0.7 0.7)
					(thickness 0.15)
				)
				(justify left bottom)
			)
		)
		(property "Value" "C_22u_25V_0805"
			(at -2.055717 1.963152 90)
			(layer "F.Fab")
			(effects
				(font
					(size 0.7 0.7)
					(thickness 0.15)
				)
				(justify left bottom)
			)
		)
		(property "Datasheet" "https://product.samsungsem.com/mlcc/CL21A226MAYNNN.do"
			(at 0 0 90)
			(layer "F.Fab")
			(hide yes)
			(effects
				(font
					(size 1.27 1.27)
					(thickness 0.15)
				)
			)
		)
		(property "MPN" "CL21A226MAYNNNE"
			(at 0 0 90)
			(unlocked yes)
			(layer "F.Fab")
			(hide yes)
			(effects
				(font
					(size 1 1)
					(thickness 0.15)
				)
			)
		)
		(property "Manufacturer" "Samsung Electro-Mechanics"
			(at 0 0 90)
			(unlocked yes)
			(layer "F.Fab")
			(hide yes)
			(effects
				(font
					(size 1 1)
					(thickness 0.15)
				)
			)
		)
		(property "License" "Apache-2.0"
			(at 0 0 90)
			(unlocked yes)
			(layer "F.Fab")
			(hide yes)
			(effects
				(font
					(size 1 1)
					(thickness 0.15)
				)
			)
		)
		(property "Author" "Antmicro"
			(at 0 0 90)
			(unlocked yes)
			(layer "F.Fab")
			(hide yes)
			(effects
				(font
					(size 1 1)
					(thickness 0.15)
				)
			)
		)
		(property "Val" "22u"
			(at 0 0 90)
			(unlocked yes)
			(layer "F.Fab")
			(hide yes)
			(effects
				(font
					(size 1 1)
					(thickness 0.15)
				)
			)
		)
		(property "Voltage" "25V"
			(at 0 0 90)
			(unlocked yes)
			(layer "F.Fab")
			(hide yes)
			(effects
				(font
					(size 1 1)
					(thickness 0.15)
				)
			)
		)
		(property "Dielectric" "X5R"
			(at 0 0 90)
			(unlocked yes)
			(layer "F.Fab")
			(hide yes)
			(effects
				(font
					(size 1 1)
					(thickness 0.15)
				)
			)
		)
		(property "Public" "False"
			(at 0 0 90)
			(unlocked yes)
			(layer "F.Fab")
			(hide yes)
			(effects
				(font
					(size 1 1)
					(thickness 0.15)
				)
			)
		)
		(sheetname "/Supply/DC-DC AUX, MGT/")
		(sheetfile "dc-dc-aux-mgt.kicad_sch")
		(attr smd)
		(fp_line
			(start -0.3 -0.7)
			(end 0.3 -0.7)
			(stroke
				(width 0.15)
				(type solid)
			)
			(layer "F.SilkS")
		)
		(fp_line
			(start -0.3 0.7)
			(end 0.3 0.7)
			(stroke
				(width 0.15)
				(type solid)
			)
			(layer "F.SilkS")
		)
		(fp_rect
			(start 1.95 -0.9)
			(end -1.95 0.9)
			(stroke
				(width 0.05)
				(type default)
			)
			(fill no)
			(layer "F.CrtYd")
		)
		(fp_rect
			(start -0.95 -0.675)
			(end 0.95 0.675)
			(stroke
				(width 0.15)
				(type solid)
			)
			(fill no)
			(layer "F.Fab")
		)
		(fp_text user "Author: Antmicro"
			(at -1.9 5.947 90)
			(layer "F.Fab")
			(effects
				(font
					(size 0.7 0.7)
					(thickness 0.15)
				)
				(justify left bottom)
			)
		)
		(fp_text user "${REFERENCE}"
			(at -1.9 3.947 90)
			(layer "F.Fab")
			(effects
				(font
					(size 0.7 0.7)
					(thickness 0.15)
				)
				(justify left bottom)
			)
		)
		(fp_text user "License: Apache-2.0"
			(at -1.9 4.947 90)
			(layer "F.Fab")
			(effects
				(font
					(size 0.7 0.7)
					(thickness 0.15)
				)
				(justify left bottom)
			)
		)
		(pad "1" smd roundrect
			(at -1.1 0 90)
			(size 1.2 1.3)
			(layers "F.Cu" "F.Mask" "F.Paste")
			(roundrect_rratio 0.25)
			(net 1 "GND")
			(pintype "passive")
		)
		(pad "2" smd roundrect
			(at 1.1 0 90)
			(size 1.2 1.3)
			(layers "F.Cu" "F.Mask" "F.Paste")
			(roundrect_rratio 0.25)
			(net 35 "VDC")
			(pintype "passive")
		)
	)
	(footprint "antmicro-footprints:C_0603_1608Metric"
		(layer "F.Cu")
		(at 149.224499 193.749 180)
		(descr "Capacitor SMD 0603")
		(tags "capacitor 0603")
		(property "Reference" "C225"
			(at -2.475501 -1.551 0)
			(layer "F.SilkS")
			(effects
				(font
					(size 0.7 0.7)
					(thickness 0.15)
				)
				(justify right bottom)
			)
		)
		(property "Value" "C_10u_25V_0603"
			(at -1.42757 1.770288 0)
			(layer "F.Fab")
			(effects
				(font
					(size 0.7 0.7)
					(thickness 0.15)
				)
				(justify right bottom)
			)
		)
		(property "Datasheet" "https://product.tdk.com/en/search/capacitor/ceramic/mlcc/info?part_no=C1608X5R1E106M080AC"
			(at 0 0 180)
			(layer "F.Fab")
			(hide yes)
			(effects
				(font
					(size 1.27 1.27)
					(thickness 0.15)
				)
			)
		)
		(property "MPN" "C1608X5R1E106M080AC"
			(at 0 0 180)
			(unlocked yes)
			(layer "F.Fab")
			(hide yes)
			(effects
				(font
					(size 1 1)
					(thickness 0.15)
				)
			)
		)
		(property "Manufacturer" "TDK"
			(at 0 0 180)
			(unlocked yes)
			(layer "F.Fab")
			(hide yes)
			(effects
				(font
					(size 1 1)
					(thickness 0.15)
				)
			)
		)
		(property "License" "Apache-2.0"
			(at 0 0 180)
			(unlocked yes)
			(layer "F.Fab")
			(hide yes)
			(effects
				(font
					(size 1 1)
					(thickness 0.15)
				)
			)
		)
		(property "Author" "Antmicro"
			(at 0 0 180)
			(unlocked yes)
			(layer "F.Fab")
			(hide yes)
			(effects
				(font
					(size 1 1)
					(thickness 0.15)
				)
			)
		)
		(property "Val" "10u"
			(at 0 0 180)
			(unlocked yes)
			(layer "F.Fab")
			(hide yes)
			(effects
				(font
					(size 1 1)
					(thickness 0.15)
				)
			)
		)
		(property "Voltage" "25V"
			(at 0 0 180)
			(unlocked yes)
			(layer "F.Fab")
			(hide yes)
			(effects
				(font
					(size 1 1)
					(thickness 0.15)
				)
			)
		)
		(property "Dielectric" ""
			(at 0 0 180)
			(unlocked yes)
			(layer "F.Fab")
			(hide yes)
			(effects
				(font
					(size 1 1)
					(thickness 0.15)
				)
			)
		)
		(sheetname "/PCIe connector/")
		(sheetfile "pcie-connector.kicad_sch")
		(attr smd)
		(fp_line
			(start -0.15 0.4)
			(end 0.15 0.4)
			(stroke
				(width 0.15)
				(type solid)
			)
			(layer "F.SilkS")
		)
		(fp_line
			(start -0.15 -0.4)
			(end 0.15 -0.4)
			(stroke
				(width 0.15)
				(type solid)
			)
			(layer "F.SilkS")
		)
		(fp_rect
			(start -1.25 -0.65)
			(end 1.25 0.65)
			(stroke
				(width 0.05)
				(type solid)
			)
			(fill no)
			(layer "F.CrtYd")
		)
		(fp_rect
			(start -0.8 -0.4)
			(end 0.8 0.4)
			(stroke
				(width 0.15)
				(type solid)
			)
			(fill no)
			(layer "F.Fab")
		)
		(fp_text user "Author: Antmicro"
			(at -1.682 4.894 180)
			(layer "F.Fab")
			(effects
				(font
					(size 0.7 0.7)
					(thickness 0.15)
				)
				(justify left bottom)
			)
		)
		(fp_text user "License: Apache-2.0"
			(at -1.682 5.895 180)
			(layer "F.Fab")
			(effects
				(font
					(size 0.7 0.7)
					(thickness 0.15)
				)
				(justify left bottom)
			)
		)
		(fp_text user "${REFERENCE}"
			(at -1.682 3.895 180)
			(layer "F.Fab")
			(effects
				(font
					(size 0.7 0.7)
					(thickness 0.15)
				)
				(justify left bottom)
			)
		)
		(pad "1" smd roundrect
			(at -0.7 0 180)
			(size 0.8 1)
			(layers "F.Cu" "F.Mask" "F.Paste")
			(roundrect_rratio 0.2)
			(net 1 "GND")
			(pintype "passive")
		)
		(pad "2" smd roundrect
			(at 0.7 0 180)
			(size 0.8 1)
			(layers "F.Cu" "F.Mask" "F.Paste")
			(roundrect_rratio 0.2)
			(net 10 "+12V")
			(pintype "passive")
		)
	)
	(footprint "antmicro-footprints:NetTie-2_SMD_Pad0.127mm"
		(layer "F.Cu")
		(at 246.877 177.55)
		(descr "Net tie, 2 pin, 0.127mm  SMD pads")
		(tags "net tie")
		(property "Reference" "NT1"
			(at -0.128 -1.345 0)
			(layer "F.SilkS")
			(hide yes)
			(effects
				(font
					(size 0.7 0.7)
					(thickness 0.15)
				)
				(justify left bottom)
			)
		)
		(property "Value" "Net-Tie_P0.127mm"
			(at 0 1.199 0)
			(layer "F.Fab")
			(effects
				(font
					(size 0.7 0.7)
					(thickness 0.15)
				)
				(justify left bottom)
			)
		)
		(property "MPN" ""
			(at 0 0 0)
			(unlocked yes)
			(layer "F.Fab")
			(hide yes)
			(effects
				(font
					(size 1 1)
					(thickness 0.15)
				)
			)
		)
		(property "Manufacturer" ""
			(at 0 0 0)
			(unlocked yes)
			(layer "F.Fab")
			(hide yes)
			(effects
				(font
					(size 1 1)
					(thickness 0.15)
				)
			)
		)
		(property "Author" "Antmicro"
			(at 0 0 0)
			(unlocked yes)
			(layer "F.Fab")
			(hide yes)
			(effects
				(font
					(size 1 1)
					(thickness 0.15)
				)
			)
		)
		(property "License" "Apache-2.0"
			(at 0 0 0)
			(unlocked yes)
			(layer "F.Fab")
			(hide yes)
			(effects
				(font
					(size 1 1)
					(thickness 0.15)
				)
			)
		)
		(property ki_fp_filters "Net*Tie*")
		(sheetname "/Supply/DC-DC AUX, MGT/")
		(sheetfile "dc-dc-aux-mgt.kicad_sch")
		(attr through_hole exclude_from_pos_files exclude_from_bom)
		(net_tie_pad_groups "1, 2")
		(fp_poly
			(pts
				(xy -0.0635 -0.0635) (xy 0.0625 -0.0635) (xy 0.0625 0.0635) (xy -0.0635 0.0635)
			)
			(stroke
				(width 0)
				(type solid)
			)
			(fill yes)
			(layer "F.Cu")
		)
		(fp_poly
			(pts
				(xy 0.2 -0.16) (xy 0.29 -0.07) (xy 0.29 0.07) (xy 0.2 0.16) (xy -0.2 0.16) (xy -0.29 0.07) (xy -0.29 -0.06)
				(xy -0.19 -0.16)
			)
			(stroke
				(width 0.05)
				(type solid)
			)
			(fill no)
			(layer "F.CrtYd")
		)
		(fp_text user "License: Apache-2.0"
			(at -0.128 5.6 0)
			(layer "F.Fab")
			(effects
				(font
					(size 0.7 0.7)
					(thickness 0.15)
				)
				(justify left bottom)
			)
		)
		(fp_text user "${REFERENCE}"
			(at -0.128 3.2 0)
			(layer "F.Fab")
			(effects
				(font
					(size 0.7 0.7)
					(thickness 0.15)
				)
				(justify left bottom)
			)
		)
		(fp_text user "Author: Antmicro"
			(at -0.128 4.4 0)
			(layer "F.Fab")
			(effects
				(font
					(size 0.7 0.7)
					(thickness 0.15)
				)
				(justify left bottom)
			)
		)
		(pad "1" smd roundrect
			(at -0.127 0 180)
			(size 0.127 0.127)
			(layers "F.Cu")
			(roundrect_rratio 0.5)
			(chamfer_ratio 0)
			(chamfer top_left bottom_left)
			(net 681 "/Supply/DC-DC AUX, MGT/1V8_SEN_+")
			(pinfunction "1")
			(pintype "passive")
		)
		(pad "2" smd roundrect
			(at 0.126 0)
			(size 0.127 0.127)
			(layers "F.Cu")
			(roundrect_rratio 0.5)
			(chamfer_ratio 0)
			(chamfer top_left bottom_left)
			(net 37 "/Supply/DC-DC AUX, MGT/1V8_local")
			(pinfunction "2")
			(pintype "passive")
		)
	)
	(footprint "antmicro-footprints:R_0603_1608Metric"
		(layer "F.Cu")
		(at 228.875 167.95 90)
		(descr "Resistor SMD 0603")
		(tags "resistor SMD 0603")
		(property "Reference" "R216"
			(at 1.175 0.5 90)
			(layer "F.SilkS")
			(effects
				(font
					(size 0.7 0.7)
					(thickness 0.15)
				)
				(justify left bottom)
			)
		)
		(property "Value" "R_0R_22.4A_0603"
			(at 0 1.6 90)
			(layer "F.Fab")
			(effects
				(font
					(size 0.7 0.7)
					(thickness 0.15)
				)
				(justify left bottom)
			)
		)
		(property "Datasheet" "https://fscdn.rohm.com/en/products/databook/datasheet/passive/resistor/chip_resistor/pmr-jpw-e.pdf"
			(at 0 0 90)
			(layer "F.Fab")
			(hide yes)
			(effects
				(font
					(size 1.27 1.27)
					(thickness 0.15)
				)
			)
		)
		(property "Manufacturer" "ROHM Semiconductor"
			(at 0 0 90)
			(unlocked yes)
			(layer "F.Fab")
			(hide yes)
			(effects
				(font
					(size 1 1)
					(thickness 0.15)
				)
			)
		)
		(property "MPN" "PMR03EZPJ000"
			(at 0 0 90)
			(unlocked yes)
			(layer "F.Fab")
			(hide yes)
			(effects
				(font
					(size 1 1)
					(thickness 0.15)
				)
			)
		)
		(property "Val" "0R"
			(at 0 0 90)
			(unlocked yes)
			(layer "F.Fab")
			(hide yes)
			(effects
				(font
					(size 1 1)
					(thickness 0.15)
				)
			)
		)
		(property "Author" "Antmicro"
			(at 0 0 90)
			(unlocked yes)
			(layer "F.Fab")
			(hide yes)
			(effects
				(font
					(size 1 1)
					(thickness 0.15)
				)
			)
		)
		(property "License" "Apache-2.0"
			(at 0 0 90)
			(unlocked yes)
			(layer "F.Fab")
			(hide yes)
			(effects
				(font
					(size 1 1)
					(thickness 0.15)
				)
			)
		)
		(property "Max. Curr." "22.4A"
			(at 0 0 90)
			(unlocked yes)
			(layer "F.Fab")
			(hide yes)
			(effects
				(font
					(size 1 1)
					(thickness 0.15)
				)
			)
		)
		(sheetname "/Supply/DC-DC VCCINT/")
		(sheetfile "dc-dc-vccint.kicad_sch")
		(attr smd)
		(fp_line
			(start -0.15 -0.4)
			(end 0.15 -0.4)
			(stroke
				(width 0.15)
				(type solid)
			)
			(layer "F.SilkS")
		)
		(fp_line
			(start -0.15 0.4)
			(end 0.15 0.4)
			(stroke
				(width 0.15)
				(type solid)
			)
			(layer "F.SilkS")
		)
		(fp_rect
			(start -1.25 -0.65)
			(end 1.25 0.65)
			(stroke
				(width 0.05)
				(type solid)
			)
			(fill no)
			(layer "F.CrtYd")
		)
		(fp_rect
			(start -0.8 -0.4)
			(end 0.8 0.4)
			(stroke
				(width 0.15)
				(type solid)
			)
			(fill no)
			(layer "F.Fab")
		)
		(fp_text user "License: Apache-2.0"
			(at -1.25 5.9 90)
			(layer "F.Fab")
			(effects
				(font
					(size 0.7 0.7)
					(thickness 0.15)
				)
				(justify left bottom)
			)
		)
		(fp_text user "Author: Antmicro"
			(at -1.25 4.9 90)
			(layer "F.Fab")
			(effects
				(font
					(size 0.7 0.7)
					(thickness 0.15)
				)
				(justify left bottom)
			)
		)
		(fp_text user "${REFERENCE}"
			(at -1.25 3.898 90)
			(layer "F.Fab")
			(effects
				(font
					(size 0.7 0.7)
					(thickness 0.15)
				)
				(justify left bottom)
			)
		)
		(pad "1" smd roundrect
			(at -0.7 0 90)
			(size 0.8 1)
			(layers "F.Cu" "F.Mask" "F.Paste")
			(roundrect_rratio 0.2)
			(net 224 "/Supply/DC-DC VCCINT/0V85_REG1")
			(pintype "passive")
		)
		(pad "2" smd roundrect
			(at 0.7 0 90)
			(size 0.8 1)
			(layers "F.Cu" "F.Mask" "F.Paste")
			(roundrect_rratio 0.2)
			(net 553 "+0V85")
			(pintype "passive")
		)
	)
	(footprint "antmicro-footprints:TP_SMD_1mm"
		(layer "F.Cu")
		(at 109.274499 137.449)
		(property "Reference" "TP22"
			(at 0 -0.731898 0)
			(layer "F.SilkS")
			(hide yes)
			(effects
				(font
					(size 0.7 0.7)
					(thickness 0.15)
				)
				(justify left bottom)
			)
		)
		(property "Value" "TP_1mm_SMD"
			(at 0 1.4 0)
			(layer "F.Fab")
			(effects
				(font
					(size 0.7 0.7)
					(thickness 0.15)
				)
				(justify left bottom)
			)
		)
		(property "MPN" ""
			(at 0 0 0)
			(unlocked yes)
			(layer "F.Fab")
			(hide yes)
			(effects
				(font
					(size 1 1)
					(thickness 0.15)
				)
			)
		)
		(property "Manufacturer" ""
			(at 0 0 0)
			(unlocked yes)
			(layer "F.Fab")
			(hide yes)
			(effects
				(font
					(size 1 1)
					(thickness 0.15)
				)
			)
		)
		(property "Author" "Antmicro"
			(at 0 0 0)
			(unlocked yes)
			(layer "F.Fab")
			(hide yes)
			(effects
				(font
					(size 1 1)
					(thickness 0.15)
				)
			)
		)
		(property "License" "Apache-2.0"
			(at 0 0 0)
			(unlocked yes)
			(layer "F.Fab")
			(hide yes)
			(effects
				(font
					(size 1 1)
					(thickness 0.15)
				)
			)
		)
		(sheetname "/Debug FTDI + VNA/")
		(sheetfile "debug-ftdi.kicad_sch")
		(attr exclude_from_pos_files)
		(fp_circle
			(center 0 0)
			(end 0.6 0)
			(stroke
				(width 0.05)
				(type default)
			)
			(fill no)
			(layer "F.CrtYd")
		)
		(fp_text user "${REFERENCE}"
			(at -0.5 2.8 0)
			(layer "F.Fab")
			(effects
				(font
					(size 0.7 0.7)
					(thickness 0.15)
				)
				(justify left bottom)
			)
		)
		(fp_text user "Author: Antmicro"
			(at -0.5 4 0)
			(layer "F.Fab")
			(effects
				(font
					(size 0.7 0.7)
					(thickness 0.15)
				)
				(justify left bottom)
			)
		)
		(fp_text user "License: Apache-2.0"
			(at -0.5 5.2 0)
			(layer "F.Fab")
			(effects
				(font
					(size 0.7 0.7)
					(thickness 0.15)
				)
				(justify left bottom)
			)
		)
		(pad "1" smd circle
			(at 0 0)
			(size 1 1)
			(layers "F.Cu" "F.Mask")
			(net 2 "/Debug FTDI + VNA/VBUS")
			(pinfunction "1")
			(pintype "passive")
		)
	)
)
